(kicad_pcb
	(version 20260206)
	(generator "pcbnew")
	(generator_version "10.0")
	(general
		(thickness 1.6)
		(legacy_teardrops no)
	)
	(paper "A4")
	(title_block
		(title "Wiwynn_Tioga_Pass_MB.brd")
		(comment 1 "Tioga Pass / footprints 1365-1365 of 4770")
	)
	(layers
		(0 "F.Cu" signal "TOP")
		(4 "In1.Cu" signal "L2GND")
		(6 "In2.Cu" signal "L3")
		(8 "In3.Cu" signal "L4GND")
		(10 "In4.Cu" signal "L5")
		(12 "In5.Cu" signal "L6GND")
		(14 "In6.Cu" signal "L7VCC")
		(16 "In7.Cu" signal "L8VCC")
		(18 "In8.Cu" signal "L9GND")
		(20 "In9.Cu" signal "L10")
		(22 "In10.Cu" signal "L11GND")
		(24 "In11.Cu" signal "L12")
		(26 "In12.Cu" signal "L13GND")
		(2 "B.Cu" signal "BOTTOM")
		(9 "F.Adhes" user "F.Adhesive")
		(11 "B.Adhes" user "B.Adhesive")
		(13 "F.Paste" user "Package Geometry/Pastemask Top")
		(15 "B.Paste" user "Package Geometry/Pastemask Bottom")
		(5 "F.SilkS" user "Ref Des/Silkscreen Top")
		(7 "B.SilkS" user "Ref Des/Silkscreen Bottom")
		(1 "F.Mask" user "Board Geometry/Soldermask Top")
		(3 "B.Mask" user "Board Geometry/Soldermask Bottom")
		(17 "Dwgs.User" user "User.Drawings")
		(19 "Cmts.User" user "User.Comments")
		(21 "Eco1.User" user "User.Eco1")
		(23 "Eco2.User" user "User.Eco2")
		(25 "Edge.Cuts" user "Board Geometry/Outline")
		(27 "Margin" user)
		(31 "F.CrtYd" user "Package Geometry/Place Bound Top")
		(29 "B.CrtYd" user "Package Geometry/Place Bound Bottom")
		(35 "F.Fab" user "Ref Des/Assembly Top")
		(33 "B.Fab" user "Ref Des/Assembly Bottom")
	)
	(footprint ""
		(layer "F.Cu")
		(at 389.6106 -64.5795)
		(property "Reference" "C7E14"
			(at 0 0 0)
			(layer "F.SilkS")
			(hide yes)
			(effects
				(font
					(size 1.27 1.27)
				)
			)
		)
		(property "Value" ""
			(at 0 0 0)
			(layer "F.Fab")
			(effects
				(font
					(size 1.27 1.27)
				)
			)
		)
		(duplicate_pad_numbers_are_jumpers no)
		(fp_poly
			(pts
				(xy 0.3048 -0.1016) (xy 0.3048 0.9906) (xy -0.3048 0.9906) (xy -0.3048 -0.1016)
			)
			(stroke
				(width 0)
				(type default)
			)
			(fill no)
			(layer "F.CrtYd")
		)
		(fp_line
			(start -0.3048 -0.1016)
			(end -0.3048 0.9906)
			(stroke
				(width 0.1)
				(type default)
			)
			(layer "F.Fab")
		)
		(fp_line
			(start -0.3048 0.9906)
			(end 0.3048 0.9906)
			(stroke
				(width 0.1)
				(type default)
			)
			(layer "F.Fab")
		)
		(fp_line
			(start 0.3048 -0.1016)
			(end -0.3048 -0.1016)
			(stroke
				(width 0.1)
				(type default)
			)
			(layer "F.Fab")
		)
		(fp_line
			(start 0.3048 0.9906)
			(end 0.3048 -0.1016)
			(stroke
				(width 0.1)
				(type default)
			)
			(layer "F.Fab")
		)
		(pad "1" smd rect
			(at 0 0)
			(size 0.508 0.508)
			(layers "F.Cu" "F.Mask" "F.Paste")
			(net "VR_P5V_STBY_VIN")
		)
		(pad "2" smd rect
			(at 0 0.889)
			(size 0.508 0.508)
			(layers "F.Cu" "F.Mask" "F.Paste")
			(net "GND")
		)
		(zone
			(layer "F.Cu")
			(hatch none 0.5)
			(connect_pads
				(clearance 0)
			)
			(min_thickness 0.25)
			(keepout
				(tracks allowed)
				(vias not_allowed)
				(pads allowed)
				(copperpour not_allowed)
				(footprints allowed)
			)
			(placement
				(enabled no)
				(sheetname "")
			)
			(fill
				(thermal_gap 0.5)
				(thermal_bridge_width 0.5)
				(island_removal_mode 0)
			)
			(polygon
				(pts
					(xy 389.3566 -64.3255) (xy 389.8646 -64.3255) (xy 389.8646 -63.9445) (xy 389.3566 -63.9445)
				)
			)
		)
		(zone
			(layer "F.Cu")
			(hatch none 0.5)
			(connect_pads
				(clearance 0)
			)
			(min_thickness 0.25)
			(keepout
				(tracks not_allowed)
				(vias allowed)
				(pads allowed)
				(copperpour not_allowed)
				(footprints allowed)
			)
			(placement
				(enabled no)
				(sheetname "")
			)
			(fill
				(thermal_gap 0.5)
				(thermal_bridge_width 0.5)
				(island_removal_mode 0)
			)
			(polygon
				(pts
					(xy 389.3566 -63.9445) (xy 389.8646 -63.9445) (xy 389.8646 -64.3255) (xy 389.3566 -64.3255)
				)
			)
		)
	)
)
